# T6G (Grand Teton) — schematic netlist excerpt (pin names and nets, part order shuffled) for the footprints in the layout excerpt that follows; sources: Cadence DE-HDL packaged netlist, KiCad conversion of 04192023_DAF0TMB3IC0_F0TG_MB_C_brd_V02_OCP.brd

H54  HOLE  EMPTY  pkg TH  page 230 : \1\ = GND
R899  Q_RES  0 5% CHIP  pkg 0402LF  page 133 : A = RST_PERST_OCP_SFF_BUF2_N ; B = RST_PERST1_OCP_SFF_N
R1471  Q_RES  4.7K 5% EMPTY  pkg 0201LF  page 287 : A = P1V8_CPU0_RT_1D ; B = JTAG_TMS_RT_CPU0_P1
R8027  Q_RES  560 1% CHIP  pkg 0402LF  page 256 : A = LED_P12V_PSU_R3 ; B = P12V_PSU

(kicad_pcb
	(version 20260206)
	(generator "pcbnew")
	(generator_version "10.0")
	(general
		(thickness 1.6)
		(legacy_teardrops no)
	)
	(paper "A4")
	(title_block
		(title "04192023_DAF0TMB3IC0_F0TG_MB_C_brd_V02_OCP.brd")
		(comment 1 "Grand Teton / footprints 3976-3979 of 8354")
	)
	(layers
		(0 "F.Cu" signal "TOP")
		(4 "In1.Cu" signal "GND")
		(6 "In2.Cu" signal "IN1")
		(8 "In3.Cu" signal "GND1")
		(10 "In4.Cu" signal "IN2")
		(12 "In5.Cu" signal "GND2")
		(14 "In6.Cu" signal "IN3")
		(16 "In7.Cu" signal "GND3")
		(18 "In8.Cu" signal "VCC")
		(20 "In9.Cu" signal "VCC1")
		(22 "In10.Cu" signal "GND4")
		(24 "In11.Cu" signal "IN4")
		(26 "In12.Cu" signal "GND5")
		(28 "In13.Cu" signal "IN5")
		(30 "In14.Cu" signal "GND6")
		(32 "In15.Cu" signal "IN6")
		(34 "In16.Cu" signal "GND7")
		(2 "B.Cu" signal "BOTTOM")
		(9 "F.Adhes" user "F.Adhesive")
		(11 "B.Adhes" user "B.Adhesive")
		(13 "F.Paste" user "Package Geometry/Pastemask Top")
		(15 "B.Paste" user "Package Geometry/Pastemask Bottom")
		(5 "F.SilkS" user "Ref Des/Silkscreen Top")
		(7 "B.SilkS" user "Ref Des/Silkscreen Bottom")
		(1 "F.Mask" user "Board Geometry/Soldermask Top")
		(3 "B.Mask" user "Board Geometry/Soldermask Bottom")
		(17 "Dwgs.User" user "User.Drawings")
		(19 "Cmts.User" user "User.Comments")
		(21 "Eco1.User" user "User.Eco1")
		(23 "Eco2.User" user "User.Eco2")
		(25 "Edge.Cuts" user "Board Geometry/Outline")
		(27 "Margin" user)
		(31 "F.CrtYd" user "Package Geometry/Place Bound Top")
		(29 "B.CrtYd" user "Package Geometry/Place Bound Bottom")
		(35 "F.Fab" user "Ref Des/Assembly Top")
		(33 "B.Fab" user "Ref Des/Assembly Bottom")
	)
	(footprint ""
		(layer "F.Cu")
		(at 352.298 -407.8732 90)
		(property "Reference" "R1471"
			(at 0 0 90)
			(layer "F.SilkS")
			(hide yes)
			(effects
				(font
					(size 1.27 1.27)
				)
			)
		)
		(property "Value" ""
			(at 0 0 90)
			(layer "F.Fab")
			(effects
				(font
					(size 1.27 1.27)
				)
			)
		)
		(duplicate_pad_numbers_are_jumpers no)
		(fp_line
			(start 0.32512 -0.175006)
			(end 0.32512 0.175006)
			(stroke
				(width 0.1)
				(type default)
			)
			(layer "F.Fab")
		)
		(fp_line
			(start -0.32512 -0.175006)
			(end 0.32512 -0.175006)
			(stroke
				(width 0.1)
				(type default)
			)
			(layer "F.Fab")
		)
		(fp_line
			(start 0.32512 0.175006)
			(end -0.32512 0.175006)
			(stroke
				(width 0.1)
				(type default)
			)
			(layer "F.Fab")
		)
		(fp_line
			(start -0.32512 0.175006)
			(end -0.32512 -0.175006)
			(stroke
				(width 0.1)
				(type default)
			)
			(layer "F.Fab")
		)
		(pad "1" smd rect
			(at -0.2667 0 90)
			(size 0.3048 0.381)
			(layers "F.Cu" "F.Mask" "F.Paste")
			(net "P1V8_CPU0_RT_1D")
		)
		(pad "2" smd rect
			(at 0.2667 0 270)
			(size 0.3048 0.381)
			(layers "F.Cu" "F.Mask" "F.Paste")
			(net "JTAG_TMS_RT_CPU0_P1")
		)
	)
	(footprint ""
		(layer "F.Cu")
		(at 348.052136 -147.904962)
		(property "Reference" "H54"
			(at -3.9116 -3.83413 0)
			(unlocked yes)
			(layer "F.SilkS")
			(effects
				(font
					(size 0.7874 0.5842)
					(thickness 0.1524)
				)
				(justify left)
			)
		)
		(property "Value" ""
			(at 0 0 0)
			(layer "F.Fab")
			(effects
				(font
					(size 1.27 1.27)
				)
			)
		)
		(duplicate_pad_numbers_are_jumpers no)
		(pad "1" thru_hole circle
			(at 0 0)
			(size 6.1976 6.1976)
			(drill 3.7338)
			(layers "*.Cu" "*.Mask")
			(remove_unused_layers no)
			(net "GND")
			(clearance -0.9779)
			(padstack
				(mode front_inner_back)
				(layer "Inner"
					(shape circle)
					(size 5.5372 5.5372)
					(clearance -0.6477)
				)
				(layer "B.Cu"
					(shape circle)
					(size 6.1976 6.1976)
					(clearance -0.9779)
				)
			)
		)
	)
	(footprint ""
		(layer "F.Cu")
		(at 213.889844 -125.643894)
		(property "Reference" "R899"
			(at 0 0 0)
			(layer "F.SilkS")
			(hide yes)
			(effects
				(font
					(size 1.27 1.27)
				)
			)
		)
		(property "Value" ""
			(at 0 0 0)
			(layer "F.Fab")
			(effects
				(font
					(size 1.27 1.27)
				)
			)
		)
		(duplicate_pad_numbers_are_jumpers no)
		(fp_line
			(start -0.7874 -0.4064)
			(end 0.7874 -0.4064)
			(stroke
				(width 0.1524)
				(type default)
			)
			(layer "F.SilkS")
		)
		(fp_line
			(start -0.7874 0.4064)
			(end -0.7874 -0.4064)
			(stroke
				(width 0.1524)
				(type default)
			)
			(layer "F.SilkS")
		)
		(fp_line
			(start 0.7874 -0.4064)
			(end 0.7874 0.4064)
			(stroke
				(width 0.1524)
				(type default)
			)
			(layer "F.SilkS")
		)
		(fp_line
			(start 0.7874 0.4064)
			(end -0.7874 0.4064)
			(stroke
				(width 0.1524)
				(type default)
			)
			(layer "F.SilkS")
		)
		(fp_line
			(start -0.67945 -0.305054)
			(end -0.12065 -0.305054)
			(stroke
				(width 0.1)
				(type default)
			)
			(layer "F.Fab")
		)
		(fp_line
			(start -0.67945 0.3048)
			(end -0.67945 -0.305054)
			(stroke
				(width 0.1)
				(type default)
			)
			(layer "F.Fab")
		)
		(fp_line
			(start -0.12065 -0.305054)
			(end -0.12065 -0.2794)
			(stroke
				(width 0.1)
				(type default)
			)
			(layer "F.Fab")
		)
		(fp_line
			(start -0.12065 -0.2794)
			(end 0.12065 -0.2794)
			(stroke
				(width 0.1)
				(type default)
			)
			(layer "F.Fab")
		)
		(fp_line
			(start -0.12065 0.2794)
			(end -0.12065 0.3048)
			(stroke
				(width 0.1)
				(type default)
			)
			(layer "F.Fab")
		)
		(fp_line
			(start -0.12065 0.3048)
			(end -0.67945 0.3048)
			(stroke
				(width 0.1)
				(type default)
			)
			(layer "F.Fab")
		)
		(fp_line
			(start 0.120396 0.2794)
			(end -0.12065 0.2794)
			(stroke
				(width 0.1)
				(type default)
			)
			(layer "F.Fab")
		)
		(fp_line
			(start 0.120396 0.3048)
			(end 0.120396 0.2794)
			(stroke
				(width 0.1)
				(type default)
			)
			(layer "F.Fab")
		)
		(fp_line
			(start 0.12065 -0.3048)
			(end 0.67945 -0.3048)
			(stroke
				(width 0.1)
				(type default)
			)
			(layer "F.Fab")
		)
		(fp_line
			(start 0.12065 -0.2794)
			(end 0.12065 -0.3048)
			(stroke
				(width 0.1)
				(type default)
			)
			(layer "F.Fab")
		)
		(fp_line
			(start 0.67945 -0.3048)
			(end 0.67945 0.3048)
			(stroke
				(width 0.1)
				(type default)
			)
			(layer "F.Fab")
		)
		(fp_line
			(start 0.67945 0.3048)
			(end 0.120396 0.3048)
			(stroke
				(width 0.1)
				(type default)
			)
			(layer "F.Fab")
		)
		(pad "1" smd circle
			(at -0.40005 0)
			(size 0 0)
			(layers "F.Cu" "F.Mask" "F.Paste")
			(net "RST_PERST_OCP_SFF_BUF2_N")
		)
		(pad "2" smd circle
			(at 0.40005 0)
			(size 0 0)
			(layers "F.Cu" "F.Mask" "F.Paste")
			(net "RST_PERST1_OCP_SFF_N")
		)
	)
	(footprint ""
		(layer "F.Cu")
		(at 184.622694 -410.144722)
		(property "Reference" "R8027"
			(at 0 0 0)
			(layer "F.SilkS")
			(hide yes)
			(effects
				(font
					(size 1.27 1.27)
				)
			)
		)
		(property "Value" ""
			(at 0 0 0)
			(layer "F.Fab")
			(effects
				(font
					(size 1.27 1.27)
				)
			)
		)
		(duplicate_pad_numbers_are_jumpers no)
		(fp_line
			(start -0.7874 -0.4064)
			(end 0.7874 -0.4064)
			(stroke
				(width 0.1524)
				(type default)
			)
			(layer "F.SilkS")
		)
		(fp_line
			(start -0.7874 0.4064)
			(end -0.7874 -0.4064)
			(stroke
				(width 0.1524)
				(type default)
			)
			(layer "F.SilkS")
		)
		(fp_line
			(start 0.7874 -0.4064)
			(end 0.7874 0.4064)
			(stroke
				(width 0.1524)
				(type default)
			)
			(layer "F.SilkS")
		)
		(fp_line
			(start 0.7874 0.4064)
			(end -0.7874 0.4064)
			(stroke
				(width 0.1524)
				(type default)
			)
			(layer "F.SilkS")
		)
		(fp_line
			(start -0.67945 -0.305054)
			(end -0.12065 -0.305054)
			(stroke
				(width 0.1)
				(type default)
			)
			(layer "F.Fab")
		)
		(fp_line
			(start -0.67945 0.3048)
			(end -0.67945 -0.305054)
			(stroke
				(width 0.1)
				(type default)
			)
			(layer "F.Fab")
		)
		(fp_line
			(start -0.12065 -0.305054)
			(end -0.12065 -0.2794)
			(stroke
				(width 0.1)
				(type default)
			)
			(layer "F.Fab")
		)
		(fp_line
			(start -0.12065 -0.2794)
			(end 0.12065 -0.2794)
			(stroke
				(width 0.1)
				(type default)
			)
			(layer "F.Fab")
		)
		(fp_line
			(start -0.12065 0.2794)
			(end -0.12065 0.3048)
			(stroke
				(width 0.1)
				(type default)
			)
			(layer "F.Fab")
		)
		(fp_line
			(start -0.12065 0.3048)
			(end -0.67945 0.3048)
			(stroke
				(width 0.1)
				(type default)
			)
			(layer "F.Fab")
		)
		(fp_line
			(start 0.120396 0.2794)
			(end -0.12065 0.2794)
			(stroke
				(width 0.1)
				(type default)
			)
			(layer "F.Fab")
		)
		(fp_line
			(start 0.120396 0.3048)
			(end 0.120396 0.2794)
			(stroke
				(width 0.1)
				(type default)
			)
			(layer "F.Fab")
		)
		(fp_line
			(start 0.12065 -0.3048)
			(end 0.67945 -0.3048)
			(stroke
				(width 0.1)
				(type default)
			)
			(layer "F.Fab")
		)
		(fp_line
			(start 0.12065 -0.2794)
			(end 0.12065 -0.3048)
			(stroke
				(width 0.1)
				(type default)
			)
			(layer "F.Fab")
		)
		(fp_line
			(start 0.67945 -0.3048)
			(end 0.67945 0.3048)
			(stroke
				(width 0.1)
				(type default)
			)
			(layer "F.Fab")
		)
		(fp_line
			(start 0.67945 0.3048)
			(end 0.120396 0.3048)
			(stroke
				(width 0.1)
				(type default)
			)
			(layer "F.Fab")
		)
		(pad "1" smd circle
			(at -0.40005 0)
			(size 0 0)
			(layers "F.Cu" "F.Mask" "F.Paste")
			(net "LED_P12V_PSU_R3")
		)
		(pad "2" smd circle
			(at 0.40005 0)
			(size 0 0)
			(layers "F.Cu" "F.Mask" "F.Paste")
			(net "P12V_PSU")
		)
	)
)
